# T6G (Grand Teton) — schematic parts with pin connectivity, parts 8081–8081 of 8303; source: Cadence DE-HDL packaged netlist (pstxprt.dat, pstxnet.dat, pstchip.dat)

U25  GENOA_SP5  SOCKET6096_13568-001 IO  pkg SOCKET6096_93-4X120-45XA  page 10  (pins 5377-5712 of 6096)
  L1  VSS_L1  POWER  = GND
  L2  MGA_DATA8  BI  = M_G_CPU0_SA_DQ<8>
  L3  MGA_DATA7  BI  = M_G_CPU0_SA_DQ<7>
  L4  VDDCR_SOC_L4  POWER  = PVDDCR_SOC_P0
  L5  MKA_DATA8  BI  = M_K_CPU0_SA_DQ<8>
  L6  VSS_L6  POWER  = GND
  L7  MKA_DATA7  BI  = M_K_CPU0_SA_DQ<7>
  L8  VSS_L8  POWER  = GND
  L9  MLA_DATA8  BI  = M_L_CPU0_SA_DQ<8>
  L10  MLA_DATA7  BI  = M_L_CPU0_SA_DQ<7>
  L11  VDDCR_SOC_L11  POWER  = PVDDCR_SOC_P0
  L12  MHA_DATA8  BI  = M_H_CPU0_SA_DQ<8>
  L13  VSS_L13  POWER  = GND
  L14  MHA_DATA7  BI  = M_H_CPU0_SA_DQ<7>
  L15  VSS_L15  POWER  = GND
  L16  MJA_DATA8  BI  = M_J_CPU0_SA_DQ<8>
  L17  MJA_DATA7  BI  = M_J_CPU0_SA_DQ<7>
  L18  VDDCR_SOC_L18  POWER  = PVDDCR_SOC_P0
  L19  MIA_DATA8  BI  = M_I_CPU0_SA_DQ<8>
  L20  VSS_L20  POWER  = GND
  L21  MIA_DATA7  BI  = M_I_CPU0_SA_DQ<7>
  L22  VSS_L22  POWER  = GND
  L23  G2_TXP3  OUT  = GMI_CPU0_G2_CPU1_G0_TX_DP<3>
  L24  G2_TXN3  OUT  = GMI_CPU0_G2_CPU1_G0_TX_DN<3>
  L25  VSS_L25  POWER  = GND
  L26  G2_TXP6  OUT  = GMI_CPU0_G2_CPU1_G0_TX_DP<6>
  L27  G2_TXN6  OUT  = GMI_CPU0_G2_CPU1_G0_TX_DN<6>
  L28  VSS_L28  POWER  = GND
  L29  G2_TXP9  OUT  = GMI_CPU0_G2_CPU1_G0_TX_DP<9>
  L30  G2_TXN9  OUT  = GMI_CPU0_G2_CPU1_G0_TX_DN<9>
  L31  VSS_L31  POWER  = GND
  L32  G2_TXP12  OUT  = GMI_CPU0_G2_CPU1_G0_TX_DP<12>
  L33  G2_TXN12  OUT  = GMI_CPU0_G2_CPU1_G0_TX_DN<12>
  L34  VSS_L34  POWER  = GND
  L35  VSS_L35  POWER  = GND
  L36  VSS_L36  POWER  = GND
  L40  VSS_L40  POWER  = GND
  L41  VSS_L41  POWER  = GND
  L42  VSS_L42  POWER  = GND
  L43  G0_RXN3  IN  = GMI_CPU1_G2_CPU0_G0_TX_DN<3>
  L44  G0_RXP3  IN  = GMI_CPU1_G2_CPU0_G0_TX_DP<3>
  L45  VSS_L45  POWER  = GND
  L46  G0_RXN6  IN  = GMI_CPU1_G2_CPU0_G0_TX_DN<6>
  L47  G0_RXP6  IN  = GMI_CPU1_G2_CPU0_G0_TX_DP<6>
  L48  VSS_L48  POWER  = GND
  L49  G0_RXN9  IN  = GMI_CPU1_G2_CPU0_G0_TX_DN<9>
  L50  G0_RXP9  IN  = GMI_CPU1_G2_CPU0_G0_TX_DP<9>
  L51  VSS_L51  POWER  = GND
  L52  G0_RXN12  IN  = GMI_CPU1_G2_CPU0_G0_TX_DN<12>
  L53  G0_RXP12  IN  = GMI_CPU1_G2_CPU0_G0_TX_DP<12>
  L54  VSS_L54  POWER  = GND
  L55  MCA_DATA7  BI  = M_C_CPU0_SA_DQ<7>
  L56  VSS_L56  POWER  = GND
  L57  MCA_DATA8  BI  = M_C_CPU0_SA_DQ<8>
  L58  VDDIO_L58  POWER  = PVDDIO_P0
  L59  MDA_DATA7  BI  = M_D_CPU0_SA_DQ<7>
  L60  MDA_DATA8  BI  = M_D_CPU0_SA_DQ<8>
  L61  VSS_L61  POWER  = GND
  L62  MBA_DATA7  BI  = M_B_CPU0_SA_DQ<7>
  L63  VSS_L63  POWER  = GND
  L64  MBA_DATA8  BI  = M_B_CPU0_SA_DQ<8>
  L65  VDDIO_L65  POWER  = PVDDIO_P0
  L66  MFA_DATA7  BI  = M_F_CPU0_SA_DQ<7>
  L67  MFA_DATA8  BI  = M_F_CPU0_SA_DQ<8>
  L68  VSS_L68  POWER  = GND
  L69  MEA_DATA7  BI  = M_E_CPU0_SA_DQ<7>
  L70  VSS_L70  POWER  = GND
  L71  MEA_DATA8  BI  = M_E_CPU0_SA_DQ<8>
  L72  VDDIO_L72  POWER  = PVDDIO_P0
  L73  MAA_DATA7  BI  = M_A_CPU0_SA_DQ<7>
  L74  MAA_DATA8  BI  = M_A_CPU0_SA_DQ<8>
  L75  VSS_L75  POWER  = GND
  M2  MGA_DATA10  BI  = M_G_CPU0_SA_DQ<10>
  M3  VSS_M3  POWER  = GND
  M4  MGA_DATA9  BI  = M_G_CPU0_SA_DQ<9>
  M5  VSS_M5  POWER  = GND
  M6  MKA_DATA10  BI  = M_K_CPU0_SA_DQ<10>
  M7  MKA_DATA9  BI  = M_K_CPU0_SA_DQ<9>
  M8  VSS_M8  POWER  = GND
  M9  MLA_DATA10  BI  = M_L_CPU0_SA_DQ<10>
  M10  VSS_M10  POWER  = GND
  M11  MLA_DATA9  BI  = M_L_CPU0_SA_DQ<9>
  M12  VSS_M12  POWER  = GND
  M13  MHA_DATA10  BI  = M_H_CPU0_SA_DQ<10>
  M14  MHA_DATA9  BI  = M_H_CPU0_SA_DQ<9>
  M15  VSS_M15  POWER  = GND
  M16  MJA_DATA10  BI  = M_J_CPU0_SA_DQ<10>
  M17  VSS_M17  POWER  = GND
  M18  MJA_DATA9  BI  = M_J_CPU0_SA_DQ<9>
  M19  VSS_M19  POWER  = GND
  M20  MIA_DATA10  BI  = M_I_CPU0_SA_DQ<10>
  M21  MIA_DATA9  BI  = M_I_CPU0_SA_DQ<9>
  M22  VSS_M22  POWER  = GND
  M23  VDDCR_CPU0_M23  POWER  = PVDDCR_CPU0_P0
  M24  VDDCR_CPU0_M24  POWER  = PVDDCR_CPU0_P0
  M25  VSS_M25  POWER  = GND
  M26  VDDCR_CPU0_M26  POWER  = PVDDCR_CPU0_P0
  M27  VDDCR_CPU0_M27  POWER  = PVDDCR_CPU0_P0
  M28  VSS_M28  POWER  = GND
  M29  VDDCR_CPU0_M29  POWER  = PVDDCR_CPU0_P0
  M30  VDDCR_CPU0_M30  POWER  = PVDDCR_CPU0_P0
  M31  VSS_M31  POWER  = GND
  M32  VDDCR_CPU0_M32  POWER  = PVDDCR_CPU0_P0
  M33  VDDCR_CPU0_M33  POWER  = PVDDCR_CPU0_P0
  M34  VSS_M34  POWER  = GND
  M35  G2_TXP15  OUT  = GMI_CPU0_G2_CPU1_G0_TX_DP<15>
  M36  G2_TXN15  OUT  = GMI_CPU0_G2_CPU1_G0_TX_DN<15>
  M37  VSS_M37  POWER  = GND
  M39  VSS_M39  POWER  = GND
  M40  G0_RXN0  IN  = GMI_CPU1_G2_CPU0_G0_TX_DN<0>
  M41  G0_RXP0  IN  = GMI_CPU1_G2_CPU0_G0_TX_DP<0>
  M42  VSS_M42  POWER  = GND
  M43  VDDCR_CPU0_M43  POWER  = PVDDCR_CPU0_P0
  M44  VDDCR_CPU0_M44  POWER  = PVDDCR_CPU0_P0
  M45  VSS_M45  POWER  = GND
  M46  VDDCR_CPU0_M46  POWER  = PVDDCR_CPU0_P0
  M47  VDDCR_CPU0_M47  POWER  = PVDDCR_CPU0_P0
  M48  VSS_M48  POWER  = GND
  M49  VDDCR_CPU0_M49  POWER  = PVDDCR_CPU0_P0
  M50  VDDCR_CPU0_M50  POWER  = PVDDCR_CPU0_P0
  M51  VSS_M51  POWER  = GND
  M52  VDDCR_CPU0_M52  POWER  = PVDDCR_CPU0_P0
  M53  VDDCR_CPU0_M53  POWER  = PVDDCR_CPU0_P0
  M54  VSS_M54  POWER  = GND
  M55  MCA_DATA9  BI  = M_C_CPU0_SA_DQ<9>
  M56  MCA_DATA10  BI  = M_C_CPU0_SA_DQ<10>
  M57  VSS_M57  POWER  = GND
  M58  MDA_DATA9  BI  = M_D_CPU0_SA_DQ<9>
  M59  VSS_M59  POWER  = GND
  M60  MDA_DATA10  BI  = M_D_CPU0_SA_DQ<10>
  M61  VSS_M61  POWER  = GND
  M62  MBA_DATA9  BI  = M_B_CPU0_SA_DQ<9>
  M63  MBA_DATA10  BI  = M_B_CPU0_SA_DQ<10>
  M64  VSS_M64  POWER  = GND
  M65  MFA_DATA9  BI  = M_F_CPU0_SA_DQ<9>
  M66  VSS_M66  POWER  = GND
  M67  MFA_DATA10  BI  = M_F_CPU0_SA_DQ<10>
  M68  VSS_M68  POWER  = GND
  M69  MEA_DATA9  BI  = M_E_CPU0_SA_DQ<9>
  M70  MEA_DATA10  BI  = M_E_CPU0_SA_DQ<10>
  M71  VSS_M71  POWER  = GND
  M72  MAA_DATA9  BI  = M_A_CPU0_SA_DQ<9>
  M73  VSS_M73  POWER  = GND
  M74  MAA_DATA10  BI  = M_A_CPU0_SA_DQ<10>
  N1  VSS_N1  POWER  = GND
  N2  MGA_DQS_H1  BI  = M_G_CPU0_SA_DQS_DP<1>
  N3  MGA_DATA11  BI  = M_G_CPU0_SA_DQ<11>
  N4  VSS_N4  POWER  = GND
  N5  MKA_DQS_H1  BI  = M_K_CPU0_SA_DQS_DP<1>
  N6  VSS_N6  POWER  = GND
  N7  MKA_DATA11  BI  = M_K_CPU0_SA_DQ<11>
  N8  VSS_N8  POWER  = GND
  N9  MLA_DQS_H1  BI  = M_L_CPU0_SA_DQS_DP<1>
  N10  MLA_DATA11  BI  = M_L_CPU0_SA_DQ<11>
  N11  VSS_N11  POWER  = GND
  N12  MHA_DQS_H1  BI  = M_H_CPU0_SA_DQS_DP<1>
  N13  VSS_N13  POWER  = GND
  N14  MHA_DATA11  BI  = M_H_CPU0_SA_DQ<11>
  N15  VSS_N15  POWER  = GND
  N16  MJA_DQS_H1  BI  = M_J_CPU0_SA_DQS_DP<1>
  N17  MJA_DATA11  BI  = M_J_CPU0_SA_DQ<11>
  N18  VSS_N18  POWER  = GND
  N19  MIA_DQS_H1  BI  = M_I_CPU0_SA_DQS_DP<1>
  N20  VSS_N20  POWER  = GND
  N21  MIA_DATA11  BI  = M_I_CPU0_SA_DQ<11>
  N22  VSS_N22  POWER  = GND
  N23  G2_TXP0  OUT  = GMI_CPU0_G2_CPU1_G0_TX_DP<0>
  N24  G2_TXN0  OUT  = GMI_CPU0_G2_CPU1_G0_TX_DN<0>
  N25  VSS_N25  POWER  = GND
  N26  \g3_txp5||sata25_txp\  OUT  = P5E_CPU0_G3_TX_DP<5>
  N27  \g3_txn5||sata25_txn\  OUT  = P5E_CPU0_G3_TX_DN<5>
  N28  VSS_N28  POWER  = GND
  N29  \g3_txp8||sata30_txp\  OUT  = P5E_CPU0_G3_TX_DP<8>
  N30  \g3_txn8||sata30_txn\  OUT  = P5E_CPU0_G3_TX_DN<8>
  N31  VSS_N31  POWER  = GND
  N32  \g3_txp11||sata33_txp\  OUT  = P5E_CPU0_G3_TX_DP<11>
  N33  \g3_txn11||sata33_txn\  OUT  = P5E_CPU0_G3_TX_DN<11>
  N34  VSS_N34  POWER  = GND
  N35  VDDCR_CPU0_N35  POWER  = PVDDCR_CPU0_P0
  N36  VDDCR_CPU0_N36  POWER  = PVDDCR_CPU0_P0
  N40  VDDCR_CPU0_N40  POWER  = PVDDCR_CPU0_P0
  N41  VDDCR_CPU0_N41  POWER  = PVDDCR_CPU0_P0
  N42  VSS_N42  POWER  = GND
  N43  G1_RXN4  IN  = GMI_CPU1_G3_CPU0_G1_TX_DN<4>
  N44  G1_RXP4  IN  = GMI_CPU1_G3_CPU0_G1_TX_DP<4>
  N45  VSS_N45  POWER  = GND
  N46  G1_RXN7  IN  = GMI_CPU1_G3_CPU0_G1_TX_DN<7>
  N47  G1_RXP7  IN  = GMI_CPU1_G3_CPU0_G1_TX_DP<7>
  N48  VSS_N48  POWER  = GND
  N49  G1_RXN10  IN  = GMI_CPU1_G3_CPU0_G1_TX_DN<10>
  N50  G1_RXP10  IN  = GMI_CPU1_G3_CPU0_G1_TX_DP<10>
  N51  VSS_N51  POWER  = GND
  N52  G0_RXN15  IN  = GMI_CPU1_G2_CPU0_G0_TX_DN<15>
  N53  G0_RXP15  IN  = GMI_CPU1_G2_CPU0_G0_TX_DP<15>
  N54  VSS_N54  POWER  = GND
  N55  MCA_DATA11  BI  = M_C_CPU0_SA_DQ<11>
  N56  VSS_N56  POWER  = GND
  N57  MCA_DQS_H1  BI  = M_C_CPU0_SA_DQS_DP<1>
  N58  VSS_N58  POWER  = GND
  N59  MDA_DATA11  BI  = M_D_CPU0_SA_DQ<11>
  N60  MDA_DQS_H1  BI  = M_D_CPU0_SA_DQS_DP<1>
  N61  VSS_N61  POWER  = GND
  N62  MBA_DATA11  BI  = M_B_CPU0_SA_DQ<11>
  N63  VSS_N63  POWER  = GND
  N64  MBA_DQS_H1  BI  = M_B_CPU0_SA_DQS_DP<1>
  N65  VSS_N65  POWER  = GND
  N66  MFA_DATA11  BI  = M_F_CPU0_SA_DQ<11>
  N67  MFA_DQS_H1  BI  = M_F_CPU0_SA_DQS_DP<1>
  N68  VSS_N68  POWER  = GND
  N69  MEA_DATA11  BI  = M_E_CPU0_SA_DQ<11>
  N70  VSS_N70  POWER  = GND
  N71  MEA_DQS_H1  BI  = M_E_CPU0_SA_DQS_DP<1>
  N72  VSS_N72  POWER  = GND
  N73  MAA_DATA11  BI  = M_A_CPU0_SA_DQ<11>
  N74  MAA_DQS_H1  BI  = M_A_CPU0_SA_DQS_DP<1>
  N75  VSS_N75  POWER  = GND
  P2  MGA_DQS_L1  BI  = M_G_CPU0_SA_DQS_DN<1>
  P3  VSS_P3  POWER  = GND
  P4  MGA_DQS_L6  BI  = M_G_CPU0_SA_DQS_DN<6>
  P5  VDDCR_SOC_P5  POWER  = PVDDCR_SOC_P0
  P6  MKA_DQS_L1  BI  = M_K_CPU0_SA_DQS_DN<1>
  P7  MKA_DQS_L6  BI  = M_K_CPU0_SA_DQS_DN<6>
  P8  VSS_P8  POWER  = GND
  P9  MLA_DQS_L1  BI  = M_L_CPU0_SA_DQS_DN<1>
  P10  VSS_P10  POWER  = GND
  P11  MLA_DQS_L6  BI  = M_L_CPU0_SA_DQS_DN<6>
  P12  VDDCR_SOC_P12  POWER  = PVDDCR_SOC_P0
  P13  MHA_DQS_L1  BI  = M_H_CPU0_SA_DQS_DN<1>
  P14  MHA_DQS_L6  BI  = M_H_CPU0_SA_DQS_DN<6>
  P15  VSS_P15  POWER  = GND
  P16  MJA_DQS_L1  BI  = M_J_CPU0_SA_DQS_DN<1>
  P17  VSS_P17  POWER  = GND
  P18  MJA_DQS_L6  BI  = M_J_CPU0_SA_DQS_DN<6>
  P19  VDDCR_SOC_P19  POWER  = PVDDCR_SOC_P0
  P20  MIA_DQS_L1  BI  = M_I_CPU0_SA_DQS_DN<1>
  P21  MIA_DQS_L6  BI  = M_I_CPU0_SA_DQS_DN<6>
  P22  VDDCR_SOC_P22  POWER  = PVDDCR_SOC_P0
  P23  VSS_P23  POWER  = GND
  P24  VSS_P24  POWER  = GND
  P25  VSS_P25  POWER  = GND
  P26  VSS_P26  POWER  = GND
  P27  VSS_P27  POWER  = GND
  P28  VSS_P28  POWER  = GND
  P29  VSS_P29  POWER  = GND
  P30  VSS_P30  POWER  = GND
  P31  VSS_P31  POWER  = GND
  P32  VSS_P32  POWER  = GND
  P33  VSS_P33  POWER  = GND
  P34  VSS_P34  POWER  = GND
  P35  \g3_txp13||sata35_txp\  OUT  = P5E_CPU0_G3_TX_DP<13>
  P36  \g3_txn13||sata35_txn\  OUT  = P5E_CPU0_G3_TX_DN<13>
  P37  VSS_P37  POWER  = GND
  P39  VSS_P39  POWER  = GND
  P40  G1_RXN2  IN  = GMI_CPU1_G3_CPU0_G1_TX_DN<2>
  P41  G1_RXP2  IN  = GMI_CPU1_G3_CPU0_G1_TX_DP<2>
  P42  VSS_P42  POWER  = GND
  P43  VSS_P43  POWER  = GND
  P44  VSS_P44  POWER  = GND
  P45  VSS_P45  POWER  = GND
  P46  VSS_P46  POWER  = GND
  P47  VSS_P47  POWER  = GND
  P48  VSS_P48  POWER  = GND
  P49  VSS_P49  POWER  = GND
  P50  VSS_P50  POWER  = GND
  P51  VSS_P51  POWER  = GND
  P52  VSS_P52  POWER  = GND
  P53  VSS_P53  POWER  = GND
  P54  VDDIO_P54  POWER  = PVDDIO_P0
  P55  MCA_DQS_L6  BI  = M_C_CPU0_SA_DQS_DN<6>
  P56  MCA_DQS_L1  BI  = M_C_CPU0_SA_DQS_DN<1>
  P57  VDDIO_P57  POWER  = PVDDIO_P0
  P58  MDA_DQS_L6  BI  = M_D_CPU0_SA_DQS_DN<6>
  P59  VSS_P59  POWER  = GND
  P60  MDA_DQS_L1  BI  = M_D_CPU0_SA_DQS_DN<1>
  P61  VSS_P61  POWER  = GND
  P62  MBA_DQS_L6  BI  = M_B_CPU0_SA_DQS_DN<6>
  P63  MBA_DQS_L1  BI  = M_B_CPU0_SA_DQS_DN<1>
  P64  VDDIO_P64  POWER  = PVDDIO_P0
  P65  MFA_DQS_L6  BI  = M_F_CPU0_SA_DQS_DN<6>
  P66  VSS_P66  POWER  = GND
  P67  MFA_DQS_L1  BI  = M_F_CPU0_SA_DQS_DN<1>
  P68  VSS_P68  POWER  = GND
  P69  MEA_DQS_L6  BI  = M_E_CPU0_SA_DQS_DN<6>
  P70  MEA_DQS_L1  BI  = M_E_CPU0_SA_DQS_DN<1>
  P71  VDDIO_P71  POWER  = PVDDIO_P0
  P72  MAA_DQS_L6  BI  = M_A_CPU0_SA_DQS_DN<6>
  P73  VSS_P73  POWER  = GND
  P74  MAA_DQS_L1  BI  = M_A_CPU0_SA_DQS_DN<1>
  R1  VSS_R1  POWER  = GND
  R2  MGA_DATA12  BI  = M_G_CPU0_SA_DQ<12>
  R3  MGA_DQS_H6  BI  = M_G_CPU0_SA_DQS_DP<6>
  R4  VSS_R4  POWER  = GND
  R5  MKA_DATA12  BI  = M_K_CPU0_SA_DQ<12>
  R6  VSS_R6  POWER  = GND
  R7  MKA_DQS_H6  BI  = M_K_CPU0_SA_DQS_DP<6>
  R8  VSS_R8  POWER  = GND
  R9  MLA_DATA12  BI  = M_L_CPU0_SA_DQ<12>
  R10  MLA_DQS_H6  BI  = M_L_CPU0_SA_DQS_DP<6>
  R11  VSS_R11  POWER  = GND
  R12  MHA_DATA12  BI  = M_H_CPU0_SA_DQ<12>
  R13  VSS_R13  POWER  = GND
  R14  MHA_DQS_H6  BI  = M_H_CPU0_SA_DQS_DP<6>
  R15  VSS_R15  POWER  = GND
  R16  MJA_DATA12  BI  = M_J_CPU0_SA_DQ<12>
  R17  MJA_DQS_H6  BI  = M_J_CPU0_SA_DQS_DP<6>
  R18  VSS_R18  POWER  = GND
  R19  MIA_DATA12  BI  = M_I_CPU0_SA_DQ<12>
  R20  VSS_R20  POWER  = GND
  R21  MIA_DQS_H6  BI  = M_I_CPU0_SA_DQS_DP<6>
  R22  VSS_R22  POWER  = GND
  R23  \g3_txp1||sata21_txp\  OUT  = P5E_CPU0_G3_TX_DP<1>
  R24  \g3_txn1||sata21_txn\  OUT  = P5E_CPU0_G3_TX_DN<1>
  R25  VSS_R25  POWER  = GND
  R26  \g3_txp4||sata24_txp\  OUT  = P5E_CPU0_G3_TX_DP<4>
  R27  \g3_txn4||sata24_txn\  OUT  = P5E_CPU0_G3_TX_DN<4>
  R28  VSS_R28  POWER  = GND
  R29  \g3_txp7||sata27_txp\  OUT  = P5E_CPU0_G3_TX_DP<7>
  R30  \g3_txn7||sata27_txn\  OUT  = P5E_CPU0_G3_TX_DN<7>
  R31  VSS_R31  POWER  = GND
  R32  \g3_txp10||sata32_txp\  OUT  = P5E_CPU0_G3_TX_DP<10>
  R33  \g3_txn10||sata32_txn\  OUT  = P5E_CPU0_G3_TX_DN<10>
  R34  VSS_R34  POWER  = GND
  R35  VSS_R35  POWER  = GND
  R36  VSS_R36  POWER  = GND
  R40  VSS_R40  POWER  = GND
  R41  VSS_R41  POWER  = GND
  R42  VSS_R42  POWER  = GND
  R43  G1_RXN5  IN  = GMI_CPU1_G3_CPU0_G1_TX_DN<5>
  R44  G1_RXP5  IN  = GMI_CPU1_G3_CPU0_G1_TX_DP<5>
  R45  VSS_R45  POWER  = GND
  R46  G1_RXN8  IN  = GMI_CPU1_G3_CPU0_G1_TX_DN<8>
  R47  G1_RXP8  IN  = GMI_CPU1_G3_CPU0_G1_TX_DP<8>
  R48  VSS_R48  POWER  = GND
  R49  G1_RXN11  IN  = GMI_CPU1_G3_CPU0_G1_TX_DN<11>
  R50  G1_RXP11  IN  = GMI_CPU1_G3_CPU0_G1_TX_DP<11>
  R51  VSS_R51  POWER  = GND
